(kicad_pcb
	(version 20260206)
	(generator "pcbnew")
	(generator_version "10.0")
	(general
		(thickness 1.6)
		(legacy_teardrops no)
	)
	(paper "A4")
	(title_block
		(title "04192023_DAF0TMB3IC0_F0TG_MB_C_brd_V02_OCP.brd")
		(comment 1 "Grand Teton / footprints 6836-6842 of 8354")
	)
	(layers
		(0 "F.Cu" signal "TOP")
		(4 "In1.Cu" signal "GND")
		(6 "In2.Cu" signal "IN1")
		(8 "In3.Cu" signal "GND1")
		(10 "In4.Cu" signal "IN2")
		(12 "In5.Cu" signal "GND2")
		(14 "In6.Cu" signal "IN3")
		(16 "In7.Cu" signal "GND3")
		(18 "In8.Cu" signal "VCC")
		(20 "In9.Cu" signal "VCC1")
		(22 "In10.Cu" signal "GND4")
		(24 "In11.Cu" signal "IN4")
		(26 "In12.Cu" signal "GND5")
		(28 "In13.Cu" signal "IN5")
		(30 "In14.Cu" signal "GND6")
		(32 "In15.Cu" signal "IN6")
		(34 "In16.Cu" signal "GND7")
		(2 "B.Cu" signal "BOTTOM")
		(9 "F.Adhes" user "F.Adhesive")
		(11 "B.Adhes" user "B.Adhesive")
		(13 "F.Paste" user "Package Geometry/Pastemask Top")
		(15 "B.Paste" user "Package Geometry/Pastemask Bottom")
		(5 "F.SilkS" user "Ref Des/Silkscreen Top")
		(7 "B.SilkS" user "Ref Des/Silkscreen Bottom")
		(1 "F.Mask" user "Board Geometry/Soldermask Top")
		(3 "B.Mask" user "Board Geometry/Soldermask Bottom")
		(17 "Dwgs.User" user "User.Drawings")
		(19 "Cmts.User" user "User.Comments")
		(21 "Eco1.User" user "User.Eco1")
		(23 "Eco2.User" user "User.Eco2")
		(25 "Edge.Cuts" user "Board Geometry/Outline")
		(27 "Margin" user)
		(31 "F.CrtYd" user "Package Geometry/Place Bound Top")
		(29 "B.CrtYd" user "Package Geometry/Place Bound Bottom")
		(35 "F.Fab" user "Ref Des/Assembly Top")
		(33 "B.Fab" user "Ref Des/Assembly Bottom")
	)
	(footprint ""
		(layer "B.Cu")
		(at 428.98695 -42.357548 180)
		(property "Reference" "R1261"
			(at 0 0 0)
			(layer "B.SilkS")
			(hide yes)
			(effects
				(font
					(size 1.27 1.27)
				)
				(justify mirror)
			)
		)
		(property "Value" ""
			(at 0 0 0)
			(layer "B.Fab")
			(effects
				(font
					(size 1.27 1.27)
				)
				(justify mirror)
			)
		)
		(duplicate_pad_numbers_are_jumpers no)
		(fp_line
			(start 0.7874 0.4064)
			(end 0.7874 -0.4064)
			(stroke
				(width 0.1524)
				(type default)
			)
			(layer "B.SilkS")
		)
		(fp_line
			(start 0.7874 -0.4064)
			(end -0.7874 -0.4064)
			(stroke
				(width 0.1524)
				(type default)
			)
			(layer "B.SilkS")
		)
		(fp_line
			(start -0.7874 0.4064)
			(end 0.7874 0.4064)
			(stroke
				(width 0.1524)
				(type default)
			)
			(layer "B.SilkS")
		)
		(fp_line
			(start -0.7874 -0.4064)
			(end -0.7874 0.4064)
			(stroke
				(width 0.1524)
				(type default)
			)
			(layer "B.SilkS")
		)
		(fp_line
			(start 0.67945 0.3048)
			(end 0.67945 -0.305054)
			(stroke
				(width 0.1)
				(type default)
			)
			(layer "B.Fab")
		)
		(fp_line
			(start 0.67945 -0.305054)
			(end 0.12065 -0.305054)
			(stroke
				(width 0.1)
				(type default)
			)
			(layer "B.Fab")
		)
		(fp_line
			(start 0.12065 0.3048)
			(end 0.67945 0.3048)
			(stroke
				(width 0.1)
				(type default)
			)
			(layer "B.Fab")
		)
		(fp_line
			(start 0.12065 0.2794)
			(end 0.12065 0.3048)
			(stroke
				(width 0.1)
				(type default)
			)
			(layer "B.Fab")
		)
		(fp_line
			(start 0.12065 -0.2794)
			(end -0.12065 -0.2794)
			(stroke
				(width 0.1)
				(type default)
			)
			(layer "B.Fab")
		)
		(fp_line
			(start 0.12065 -0.305054)
			(end 0.12065 -0.2794)
			(stroke
				(width 0.1)
				(type default)
			)
			(layer "B.Fab")
		)
		(fp_line
			(start -0.120396 0.3048)
			(end -0.120396 0.2794)
			(stroke
				(width 0.1)
				(type default)
			)
			(layer "B.Fab")
		)
		(fp_line
			(start -0.120396 0.2794)
			(end 0.12065 0.2794)
			(stroke
				(width 0.1)
				(type default)
			)
			(layer "B.Fab")
		)
		(fp_line
			(start -0.12065 -0.2794)
			(end -0.12065 -0.3048)
			(stroke
				(width 0.1)
				(type default)
			)
			(layer "B.Fab")
		)
		(fp_line
			(start -0.12065 -0.3048)
			(end -0.67945 -0.3048)
			(stroke
				(width 0.1)
				(type default)
			)
			(layer "B.Fab")
		)
		(fp_line
			(start -0.67945 0.3048)
			(end -0.120396 0.3048)
			(stroke
				(width 0.1)
				(type default)
			)
			(layer "B.Fab")
		)
		(fp_line
			(start -0.67945 -0.3048)
			(end -0.67945 0.3048)
			(stroke
				(width 0.1)
				(type default)
			)
			(layer "B.Fab")
		)
		(pad "1" smd circle
			(at 0.40005 0)
			(size 0 0)
			(layers "B.Cu" "B.Mask" "B.Paste")
			(net "P1V8_AUX")
		)
		(pad "2" smd circle
			(at -0.40005 0)
			(size 0 0)
			(layers "B.Cu" "B.Mask" "B.Paste")
			(net "FM_SPD_CPU0_SWITCH_CTRL_N")
		)
	)
	(footprint ""
		(layer "B.Cu")
		(at 285.732982 -244.08511 180)
		(property "Reference" "R378"
			(at 0 0 0)
			(layer "B.SilkS")
			(hide yes)
			(effects
				(font
					(size 1.27 1.27)
				)
				(justify mirror)
			)
		)
		(property "Value" ""
			(at 0 0 0)
			(layer "B.Fab")
			(effects
				(font
					(size 1.27 1.27)
				)
				(justify mirror)
			)
		)
		(duplicate_pad_numbers_are_jumpers no)
		(fp_line
			(start 0.7874 0.4064)
			(end 0.7874 -0.4064)
			(stroke
				(width 0.1524)
				(type default)
			)
			(layer "B.SilkS")
		)
		(fp_line
			(start 0.7874 -0.4064)
			(end -0.7874 -0.4064)
			(stroke
				(width 0.1524)
				(type default)
			)
			(layer "B.SilkS")
		)
		(fp_line
			(start -0.7874 0.4064)
			(end 0.7874 0.4064)
			(stroke
				(width 0.1524)
				(type default)
			)
			(layer "B.SilkS")
		)
		(fp_line
			(start -0.7874 -0.4064)
			(end -0.7874 0.4064)
			(stroke
				(width 0.1524)
				(type default)
			)
			(layer "B.SilkS")
		)
		(fp_line
			(start 0.67945 0.3048)
			(end 0.67945 -0.305054)
			(stroke
				(width 0.1)
				(type default)
			)
			(layer "B.Fab")
		)
		(fp_line
			(start 0.67945 -0.305054)
			(end 0.12065 -0.305054)
			(stroke
				(width 0.1)
				(type default)
			)
			(layer "B.Fab")
		)
		(fp_line
			(start 0.12065 0.3048)
			(end 0.67945 0.3048)
			(stroke
				(width 0.1)
				(type default)
			)
			(layer "B.Fab")
		)
		(fp_line
			(start 0.12065 0.2794)
			(end 0.12065 0.3048)
			(stroke
				(width 0.1)
				(type default)
			)
			(layer "B.Fab")
		)
		(fp_line
			(start 0.12065 -0.2794)
			(end -0.12065 -0.2794)
			(stroke
				(width 0.1)
				(type default)
			)
			(layer "B.Fab")
		)
		(fp_line
			(start 0.12065 -0.305054)
			(end 0.12065 -0.2794)
			(stroke
				(width 0.1)
				(type default)
			)
			(layer "B.Fab")
		)
		(fp_line
			(start -0.120396 0.3048)
			(end -0.120396 0.2794)
			(stroke
				(width 0.1)
				(type default)
			)
			(layer "B.Fab")
		)
		(fp_line
			(start -0.120396 0.2794)
			(end 0.12065 0.2794)
			(stroke
				(width 0.1)
				(type default)
			)
			(layer "B.Fab")
		)
		(fp_line
			(start -0.12065 -0.2794)
			(end -0.12065 -0.3048)
			(stroke
				(width 0.1)
				(type default)
			)
			(layer "B.Fab")
		)
		(fp_line
			(start -0.12065 -0.3048)
			(end -0.67945 -0.3048)
			(stroke
				(width 0.1)
				(type default)
			)
			(layer "B.Fab")
		)
		(fp_line
			(start -0.67945 0.3048)
			(end -0.120396 0.3048)
			(stroke
				(width 0.1)
				(type default)
			)
			(layer "B.Fab")
		)
		(fp_line
			(start -0.67945 -0.3048)
			(end -0.67945 0.3048)
			(stroke
				(width 0.1)
				(type default)
			)
			(layer "B.Fab")
		)
		(pad "1" smd circle
			(at 0.40005 0)
			(size 0 0)
			(layers "B.Cu" "B.Mask" "B.Paste")
			(net "M_D_CPU0_ALERT_N")
		)
		(pad "2" smd circle
			(at -0.40005 0)
			(size 0 0)
			(layers "B.Cu" "B.Mask" "B.Paste")
			(net "M_D_CPU0_ALERT_R_N")
		)
	)
	(footprint ""
		(layer "B.Cu")
		(at 356.567232 -261.747762 90)
		(property "Reference" "C2609"
			(at 0 0 90)
			(layer "B.SilkS")
			(hide yes)
			(effects
				(font
					(size 1.27 1.27)
				)
				(justify mirror)
			)
		)
		(property "Value" ""
			(at 0 0 90)
			(layer "B.Fab")
			(effects
				(font
					(size 1.27 1.27)
				)
				(justify mirror)
			)
		)
		(duplicate_pad_numbers_are_jumpers no)
		(fp_line
			(start 0.7874 -0.4064)
			(end -0.7874 -0.4064)
			(stroke
				(width 0.1524)
				(type default)
			)
			(layer "B.SilkS")
		)
		(fp_line
			(start -0.7874 -0.4064)
			(end -0.7874 0.4064)
			(stroke
				(width 0.1524)
				(type default)
			)
			(layer "B.SilkS")
		)
		(fp_line
			(start 0.7874 0.4064)
			(end 0.7874 -0.4064)
			(stroke
				(width 0.1524)
				(type default)
			)
			(layer "B.SilkS")
		)
		(fp_line
			(start -0.7874 0.4064)
			(end 0.7874 0.4064)
			(stroke
				(width 0.1524)
				(type default)
			)
			(layer "B.SilkS")
		)
		(fp_line
			(start 0.67945 -0.305054)
			(end 0.12065 -0.305054)
			(stroke
				(width 0.1)
				(type default)
			)
			(layer "B.Fab")
		)
		(fp_line
			(start 0.12065 -0.305054)
			(end 0.12065 -0.2794)
			(stroke
				(width 0.1)
				(type default)
			)
			(layer "B.Fab")
		)
		(fp_line
			(start -0.12065 -0.3048)
			(end -0.67945 -0.3048)
			(stroke
				(width 0.1)
				(type default)
			)
			(layer "B.Fab")
		)
		(fp_line
			(start -0.67945 -0.3048)
			(end -0.67945 0.3048)
			(stroke
				(width 0.1)
				(type default)
			)
			(layer "B.Fab")
		)
		(fp_line
			(start 0.12065 -0.2794)
			(end -0.12065 -0.2794)
			(stroke
				(width 0.1)
				(type default)
			)
			(layer "B.Fab")
		)
		(fp_line
			(start -0.12065 -0.2794)
			(end -0.12065 -0.3048)
			(stroke
				(width 0.1)
				(type default)
			)
			(layer "B.Fab")
		)
		(fp_line
			(start 0.12065 0.2794)
			(end 0.12065 0.3048)
			(stroke
				(width 0.1)
				(type default)
			)
			(layer "B.Fab")
		)
		(fp_line
			(start -0.120396 0.2794)
			(end 0.12065 0.2794)
			(stroke
				(width 0.1)
				(type default)
			)
			(layer "B.Fab")
		)
		(fp_line
			(start 0.67945 0.3048)
			(end 0.67945 -0.305054)
			(stroke
				(width 0.1)
				(type default)
			)
			(layer "B.Fab")
		)
		(fp_line
			(start 0.12065 0.3048)
			(end 0.67945 0.3048)
			(stroke
				(width 0.1)
				(type default)
			)
			(layer "B.Fab")
		)
		(fp_line
			(start -0.120396 0.3048)
			(end -0.120396 0.2794)
			(stroke
				(width 0.1)
				(type default)
			)
			(layer "B.Fab")
		)
		(fp_line
			(start -0.67945 0.3048)
			(end -0.120396 0.3048)
			(stroke
				(width 0.1)
				(type default)
			)
			(layer "B.Fab")
		)
		(pad "1" smd circle
			(at 0.40005 0 270)
			(size 0 0)
			(layers "B.Cu" "B.Mask" "B.Paste")
			(net "PVDD11_S3_P0")
		)
		(pad "2" smd circle
			(at -0.40005 0 270)
			(size 0 0)
			(layers "B.Cu" "B.Mask" "B.Paste")
			(net "GND")
		)
	)
	(footprint ""
		(layer "B.Cu")
		(at 171.195492 -102.780084 180)
		(property "Reference" "R6147"
			(at 0 0 0)
			(layer "B.SilkS")
			(hide yes)
			(effects
				(font
					(size 1.27 1.27)
				)
				(justify mirror)
			)
		)
		(property "Value" ""
			(at 0 0 0)
			(layer "B.Fab")
			(effects
				(font
					(size 1.27 1.27)
				)
				(justify mirror)
			)
		)
		(duplicate_pad_numbers_are_jumpers no)
		(fp_line
			(start 0.7874 0.4064)
			(end 0.7874 -0.4064)
			(stroke
				(width 0.1524)
				(type default)
			)
			(layer "B.SilkS")
		)
		(fp_line
			(start 0.7874 -0.4064)
			(end -0.7874 -0.4064)
			(stroke
				(width 0.1524)
				(type default)
			)
			(layer "B.SilkS")
		)
		(fp_line
			(start -0.7874 0.4064)
			(end 0.7874 0.4064)
			(stroke
				(width 0.1524)
				(type default)
			)
			(layer "B.SilkS")
		)
		(fp_line
			(start -0.7874 -0.4064)
			(end -0.7874 0.4064)
			(stroke
				(width 0.1524)
				(type default)
			)
			(layer "B.SilkS")
		)
		(fp_line
			(start 0.67945 0.3048)
			(end 0.67945 -0.305054)
			(stroke
				(width 0.1)
				(type default)
			)
			(layer "B.Fab")
		)
		(fp_line
			(start 0.67945 -0.305054)
			(end 0.12065 -0.305054)
			(stroke
				(width 0.1)
				(type default)
			)
			(layer "B.Fab")
		)
		(fp_line
			(start 0.12065 0.3048)
			(end 0.67945 0.3048)
			(stroke
				(width 0.1)
				(type default)
			)
			(layer "B.Fab")
		)
		(fp_line
			(start 0.12065 0.2794)
			(end 0.12065 0.3048)
			(stroke
				(width 0.1)
				(type default)
			)
			(layer "B.Fab")
		)
		(fp_line
			(start 0.12065 -0.2794)
			(end -0.12065 -0.2794)
			(stroke
				(width 0.1)
				(type default)
			)
			(layer "B.Fab")
		)
		(fp_line
			(start 0.12065 -0.305054)
			(end 0.12065 -0.2794)
			(stroke
				(width 0.1)
				(type default)
			)
			(layer "B.Fab")
		)
		(fp_line
			(start -0.120396 0.3048)
			(end -0.120396 0.2794)
			(stroke
				(width 0.1)
				(type default)
			)
			(layer "B.Fab")
		)
		(fp_line
			(start -0.120396 0.2794)
			(end 0.12065 0.2794)
			(stroke
				(width 0.1)
				(type default)
			)
			(layer "B.Fab")
		)
		(fp_line
			(start -0.12065 -0.2794)
			(end -0.12065 -0.3048)
			(stroke
				(width 0.1)
				(type default)
			)
			(layer "B.Fab")
		)
		(fp_line
			(start -0.12065 -0.3048)
			(end -0.67945 -0.3048)
			(stroke
				(width 0.1)
				(type default)
			)
			(layer "B.Fab")
		)
		(fp_line
			(start -0.67945 0.3048)
			(end -0.120396 0.3048)
			(stroke
				(width 0.1)
				(type default)
			)
			(layer "B.Fab")
		)
		(fp_line
			(start -0.67945 -0.3048)
			(end -0.67945 0.3048)
			(stroke
				(width 0.1)
				(type default)
			)
			(layer "B.Fab")
		)
		(pad "1" smd circle
			(at 0.40005 0)
			(size 0 0)
			(layers "B.Cu" "B.Mask" "B.Paste")
			(net "P1V8_AUX")
		)
		(pad "2" smd circle
			(at -0.40005 0)
			(size 0 0)
			(layers "B.Cu" "B.Mask" "B.Paste")
			(net "FAB_BMC_REV_ID1")
		)
	)
	(footprint ""
		(layer "B.Cu")
		(at 329.459082 -326.30745 -90)
		(property "Reference" "PC106_2"
			(at 0 0 90)
			(layer "B.SilkS")
			(hide yes)
			(effects
				(font
					(size 1.27 1.27)
				)
				(justify mirror)
			)
		)
		(property "Value" ""
			(at 0 0 90)
			(layer "B.Fab")
			(effects
				(font
					(size 1.27 1.27)
				)
				(justify mirror)
			)
		)
		(duplicate_pad_numbers_are_jumpers no)
		(fp_line
			(start -1.524 0.762)
			(end 1.524 0.762)
			(stroke
				(width 0.1524)
				(type default)
			)
			(layer "B.SilkS")
		)
		(fp_line
			(start 1.524 0.762)
			(end 1.524 -0.762)
			(stroke
				(width 0.1524)
				(type default)
			)
			(layer "B.SilkS")
		)
		(fp_line
			(start -1.524 -0.762)
			(end -1.524 0.762)
			(stroke
				(width 0.1524)
				(type default)
			)
			(layer "B.SilkS")
		)
		(fp_line
			(start 1.524 -0.762)
			(end -1.524 -0.762)
			(stroke
				(width 0.1524)
				(type default)
			)
			(layer "B.SilkS")
		)
		(fp_line
			(start -1.1049 0.724916)
			(end -1.1049 -0.724916)
			(stroke
				(width 0.1)
				(type default)
			)
			(layer "B.Fab")
		)
		(fp_line
			(start 1.1049 0.724916)
			(end -1.1049 0.724916)
			(stroke
				(width 0.1)
				(type default)
			)
			(layer "B.Fab")
		)
		(fp_line
			(start -1.1049 -0.724916)
			(end 1.1049 -0.724916)
			(stroke
				(width 0.1)
				(type default)
			)
			(layer "B.Fab")
		)
		(fp_line
			(start 1.1049 -0.724916)
			(end 1.1049 0.724916)
			(stroke
				(width 0.1)
				(type default)
			)
			(layer "B.Fab")
		)
		(pad "1" smd rect
			(at 0.889 0 270)
			(size 1.016 1.27)
			(layers "B.Cu" "B.Mask" "B.Paste")
			(net "PVDDCR_CPU1_P0")
		)
		(pad "2" smd rect
			(at -0.889 0 270)
			(size 1.016 1.27)
			(layers "B.Cu" "B.Mask" "B.Paste")
			(net "GND")
		)
	)
	(footprint ""
		(layer "B.Cu")
		(at 330.731876 -66.708782 90)
		(property "Reference" "R3092"
			(at 0 0 90)
			(layer "B.SilkS")
			(hide yes)
			(effects
				(font
					(size 1.27 1.27)
				)
				(justify mirror)
			)
		)
		(property "Value" ""
			(at 0 0 90)
			(layer "B.Fab")
			(effects
				(font
					(size 1.27 1.27)
				)
				(justify mirror)
			)
		)
		(duplicate_pad_numbers_are_jumpers no)
		(fp_line
			(start 0.7874 -0.4064)
			(end -0.7874 -0.4064)
			(stroke
				(width 0.1524)
				(type default)
			)
			(layer "B.SilkS")
		)
		(fp_line
			(start -0.7874 -0.4064)
			(end -0.7874 0.4064)
			(stroke
				(width 0.1524)
				(type default)
			)
			(layer "B.SilkS")
		)
		(fp_line
			(start 0.7874 0.4064)
			(end 0.7874 -0.4064)
			(stroke
				(width 0.1524)
				(type default)
			)
			(layer "B.SilkS")
		)
		(fp_line
			(start -0.7874 0.4064)
			(end 0.7874 0.4064)
			(stroke
				(width 0.1524)
				(type default)
			)
			(layer "B.SilkS")
		)
		(fp_line
			(start 0.67945 -0.305054)
			(end 0.12065 -0.305054)
			(stroke
				(width 0.1)
				(type default)
			)
			(layer "B.Fab")
		)
		(fp_line
			(start 0.12065 -0.305054)
			(end 0.12065 -0.2794)
			(stroke
				(width 0.1)
				(type default)
			)
			(layer "B.Fab")
		)
		(fp_line
			(start -0.12065 -0.3048)
			(end -0.67945 -0.3048)
			(stroke
				(width 0.1)
				(type default)
			)
			(layer "B.Fab")
		)
		(fp_line
			(start -0.67945 -0.3048)
			(end -0.67945 0.3048)
			(stroke
				(width 0.1)
				(type default)
			)
			(layer "B.Fab")
		)
		(fp_line
			(start 0.12065 -0.2794)
			(end -0.12065 -0.2794)
			(stroke
				(width 0.1)
				(type default)
			)
			(layer "B.Fab")
		)
		(fp_line
			(start -0.12065 -0.2794)
			(end -0.12065 -0.3048)
			(stroke
				(width 0.1)
				(type default)
			)
			(layer "B.Fab")
		)
		(fp_line
			(start 0.12065 0.2794)
			(end 0.12065 0.3048)
			(stroke
				(width 0.1)
				(type default)
			)
			(layer "B.Fab")
		)
		(fp_line
			(start -0.120396 0.2794)
			(end 0.12065 0.2794)
			(stroke
				(width 0.1)
				(type default)
			)
			(layer "B.Fab")
		)
		(fp_line
			(start 0.67945 0.3048)
			(end 0.67945 -0.305054)
			(stroke
				(width 0.1)
				(type default)
			)
			(layer "B.Fab")
		)
		(fp_line
			(start 0.12065 0.3048)
			(end 0.67945 0.3048)
			(stroke
				(width 0.1)
				(type default)
			)
			(layer "B.Fab")
		)
		(fp_line
			(start -0.120396 0.3048)
			(end -0.120396 0.2794)
			(stroke
				(width 0.1)
				(type default)
			)
			(layer "B.Fab")
		)
		(fp_line
			(start -0.67945 0.3048)
			(end -0.120396 0.3048)
			(stroke
				(width 0.1)
				(type default)
			)
			(layer "B.Fab")
		)
		(pad "1" smd circle
			(at 0.40005 0 270)
			(size 0 0)
			(layers "B.Cu" "B.Mask" "B.Paste")
			(net "LED_PWRGD_PVDDIO_P0_R")
		)
		(pad "2" smd circle
			(at -0.40005 0 270)
			(size 0 0)
			(layers "B.Cu" "B.Mask" "B.Paste")
			(net "P3V3_AUX")
		)
	)
	(footprint ""
		(layer "B.Cu")
		(at 403.14626 -396.393162 -90)
		(property "Reference" "C968"
			(at 0 0 90)
			(layer "B.SilkS")
			(hide yes)
			(effects
				(font
					(size 1.27 1.27)
				)
				(justify mirror)
			)
		)
		(property "Value" ""
			(at 0 0 90)
			(layer "B.Fab")
			(effects
				(font
					(size 1.27 1.27)
				)
				(justify mirror)
			)
		)
		(duplicate_pad_numbers_are_jumpers no)
		(fp_line
			(start -0.299974 0.150114)
			(end 0.299974 0.150114)
			(stroke
				(width 0.1)
				(type default)
			)
			(layer "B.Fab")
		)
		(fp_line
			(start 0.299974 0.150114)
			(end 0.299974 -0.150114)
			(stroke
				(width 0.1)
				(type default)
			)
			(layer "B.Fab")
		)
		(fp_line
			(start -0.299974 -0.150114)
			(end -0.299974 0.150114)
			(stroke
				(width 0.1)
				(type default)
			)
			(layer "B.Fab")
		)
		(fp_line
			(start 0.299974 -0.150114)
			(end -0.299974 -0.150114)
			(stroke
				(width 0.1)
				(type default)
			)
			(layer "B.Fab")
		)
		(pad "1" smd rect
			(at 0.2667 0 90)
			(size 0.3048 0.381)
			(layers "B.Cu" "B.Mask" "B.Paste")
			(net "P0V9_CPU0_RT2_2A")
		)
		(pad "2" smd rect
			(at -0.2667 0 90)
			(size 0.3048 0.381)
			(layers "B.Cu" "B.Mask" "B.Paste")
			(net "GND")
		)
	)
)
